(kicad_pcb
	(version 20241229)
	(generator "pcbnew")
	(generator_version "9.0")
	(general
		(thickness 1.294)
		(legacy_teardrops no)
	)
	(paper "A3")
	(title_block
		(title "Kintex 410T devboard")
		(date "2024-04-03")
		(rev "1.1.2")
		(comment 9 "footprints 485-489 of 975")
	)
	(layers
		(0 "F.Cu" mixed)
		(4 "In1.Cu" power)
		(6 "In2.Cu" power)
		(8 "In3.Cu" mixed)
		(10 "In4.Cu" power)
		(12 "In5.Cu" mixed)
		(14 "In6.Cu" power)
		(16 "In7.Cu" mixed)
		(18 "In8.Cu" power)
		(2 "B.Cu" mixed)
		(9 "F.Adhes" user "F.Adhesive")
		(11 "B.Adhes" user "B.Adhesive")
		(13 "F.Paste" user)
		(15 "B.Paste" user)
		(5 "F.SilkS" user "F.Silkscreen")
		(7 "B.SilkS" user "B.Silkscreen")
		(1 "F.Mask" user)
		(3 "B.Mask" user)
		(17 "Dwgs.User" user "User.Drawings")
		(19 "Cmts.User" user "User.Comments")
		(21 "Eco1.User" user "User.Eco1")
		(23 "Eco2.User" user "User.Eco2")
		(25 "Edge.Cuts" user)
		(27 "Margin" user)
		(31 "F.CrtYd" user "F.Courtyard")
		(29 "B.CrtYd" user "B.Courtyard")
		(35 "F.Fab" user)
		(33 "B.Fab" user)
	)
	(footprint "antmicro-footprints:USON-10_2.5x1mm_P0.5mm"
		(layer "F.Cu")
		(at 261.7 127 180)
		(descr "USON-10 2.5x1mm_ Pitch 0.5mm")
		(tags "USON-10 2.5x1mm Pitch 0.5mm")
		(property "Reference" "U21"
			(at 0.95 -2.45 180)
			(layer "F.SilkS")
			(effects
				(font
					(size 0.7 0.7)
					(thickness 0.15)
				)
				(justify left bottom)
			)
		)
		(property "Value" "TPD4E05U06QDQARQ1"
			(at 0.018 2.499 180)
			(layer "F.Fab")
			(effects
				(font
					(size 0.7 0.7)
					(thickness 0.15)
				)
				(justify left bottom)
			)
		)
		(property "Description" "ESD protection"
			(at 0 0 180)
			(layer "F.Fab")
			(hide yes)
			(effects
				(font
					(size 1.27 1.27)
					(thickness 0.15)
				)
			)
		)
		(property "Author" "Antmicro"
			(at 523.4 254 0)
			(layer "F.Fab")
			(hide yes)
			(effects
				(font
					(size 1 1)
					(thickness 0.15)
				)
			)
		)
		(property "License" "Apache-2.0"
			(at 523.4 254 0)
			(layer "F.Fab")
			(hide yes)
			(effects
				(font
					(size 1 1)
					(thickness 0.15)
				)
			)
		)
		(property "MPN" "TPD4E05U06QDQARQ1"
			(at 523.4 254 0)
			(layer "F.Fab")
			(hide yes)
			(effects
				(font
					(size 1 1)
					(thickness 0.15)
				)
			)
		)
		(property "Manufacturer" "Texas Instruments"
			(at 523.4 254 0)
			(layer "F.Fab")
			(hide yes)
			(effects
				(font
					(size 1 1)
					(thickness 0.15)
				)
			)
		)
		(sheetname "USB PHY")
		(sheetfile "usb-phy.kicad_sch")
		(attr smd)
		(fp_line
			(start 0.498 1.398)
			(end -0.5 1.398)
			(stroke
				(width 0.15)
				(type solid)
			)
			(layer "F.SilkS")
		)
		(fp_line
			(start 0.498 -1.401)
			(end -0.5 -1.401)
			(stroke
				(width 0.15)
				(type solid)
			)
			(layer "F.SilkS")
		)
		(fp_circle
			(center -0.68 -1.27)
			(end -0.63 -1.27)
			(stroke
				(width 0.15)
				(type solid)
			)
			(fill yes)
			(layer "F.SilkS")
		)
		(fp_rect
			(start -0.8 -1.5)
			(end 0.8 1.499)
			(stroke
				(width 0.05)
				(type solid)
			)
			(fill no)
			(layer "F.CrtYd")
		)
		(fp_line
			(start 0.498 -1.25)
			(end 0.498 1.249)
			(stroke
				(width 0.15)
				(type solid)
			)
			(layer "F.Fab")
		)
		(fp_line
			(start 0.498 -1.25)
			(end -0.25 -1.25)
			(stroke
				(width 0.15)
				(type solid)
			)
			(layer "F.Fab")
		)
		(fp_line
			(start -0.25 -1.25)
			(end -0.5 -1)
			(stroke
				(width 0.15)
				(type solid)
			)
			(layer "F.Fab")
		)
		(fp_line
			(start -0.5 1.249)
			(end 0.498 1.249)
			(stroke
				(width 0.15)
				(type solid)
			)
			(layer "F.Fab")
		)
		(fp_line
			(start -0.5 -1)
			(end -0.5 1.249)
			(stroke
				(width 0.15)
				(type solid)
			)
			(layer "F.Fab")
		)
		(pad "1" smd roundrect
			(at -0.387 -1 90)
			(size 0.25 0.55)
			(layers "F.Cu" "F.Mask" "F.Paste")
			(roundrect_rratio 0.25)
			(net 841 "/USB PHY/USB_USR_CC1")
			(pintype "passive")
		)
		(pad "2" smd roundrect
			(at -0.387 -0.5 90)
			(size 0.25 0.55)
			(layers "F.Cu" "F.Mask" "F.Paste")
			(roundrect_rratio 0.25)
			(net 842 "/USB PHY/USB_USR_CONN_D+")
			(pintype "passive")
		)
		(pad "3" smd roundrect
			(at -0.387 0 90)
			(size 0.4 0.55)
			(layers "F.Cu" "F.Mask" "F.Paste")
			(roundrect_rratio 0.25)
			(net 1 "GND")
			(pintype "power_in")
		)
		(pad "4" smd roundrect
			(at -0.387 0.498 90)
			(size 0.25 0.55)
			(layers "F.Cu" "F.Mask" "F.Paste")
			(roundrect_rratio 0.25)
			(net 843 "/USB PHY/USB_USR_CONN_D-")
			(pintype "passive")
		)
		(pad "5" smd roundrect
			(at -0.387 0.998 90)
			(size 0.25 0.55)
			(layers "F.Cu" "F.Mask" "F.Paste")
			(roundrect_rratio 0.25)
			(net 844 "/USB PHY/USB_USR_CC2")
			(pintype "passive")
		)
		(pad "6" smd roundrect
			(at 0.385 0.998 90)
			(size 0.25 0.55)
			(layers "F.Cu" "F.Mask" "F.Paste")
			(roundrect_rratio 0.25)
			(net 844 "/USB PHY/USB_USR_CC2")
			(pintype "passive")
		)
		(pad "7" smd roundrect
			(at 0.385 0.498 90)
			(size 0.25 0.55)
			(layers "F.Cu" "F.Mask" "F.Paste")
			(roundrect_rratio 0.25)
			(net 843 "/USB PHY/USB_USR_CONN_D-")
			(pintype "passive")
		)
		(pad "8" smd roundrect
			(at 0.385 0 90)
			(size 0.4 0.55)
			(layers "F.Cu" "F.Mask" "F.Paste")
			(roundrect_rratio 0.25)
			(net 1 "GND")
			(pintype "passive")
		)
		(pad "9" smd roundrect
			(at 0.385 -0.5 90)
			(size 0.25 0.55)
			(layers "F.Cu" "F.Mask" "F.Paste")
			(roundrect_rratio 0.25)
			(net 842 "/USB PHY/USB_USR_CONN_D+")
			(pintype "passive")
		)
		(pad "10" smd roundrect
			(at 0.385 -1 90)
			(size 0.25 0.55)
			(layers "F.Cu" "F.Mask" "F.Paste")
			(roundrect_rratio 0.25)
			(net 841 "/USB PHY/USB_USR_CC1")
			(pintype "passive")
		)
	)
	(footprint "antmicro-footprints:R_0402_1005Metric"
		(layer "F.Cu")
		(at 259.6 125.5 180)
		(descr "Resistor SMD 0402")
		(tags "resistor SMD 0402")
		(property "Reference" "R362"
			(at 1.05 5.65 180)
			(layer "F.SilkS")
			(effects
				(font
					(size 0.7 0.7)
					(thickness 0.15)
				)
				(justify left bottom)
			)
		)
		(property "Value" "R_5k1_0402"
			(at 0 1.4 180)
			(layer "F.Fab")
			(effects
				(font
					(size 0.7 0.7)
					(thickness 0.15)
				)
				(justify left bottom)
			)
		)
		(property "Description" "SMD Chip Resistor, 5.1 kohm, ± 1%, 63 mW, 0402 [1005 Metric], Thick Film, General Purpose"
			(at 0 0 180)
			(layer "F.Fab")
			(hide yes)
			(effects
				(font
					(size 1.27 1.27)
					(thickness 0.15)
				)
			)
		)
		(property "Author" "Antmicro"
			(at 519.2 251 0)
			(layer "F.Fab")
			(hide yes)
			(effects
				(font
					(size 1 1)
					(thickness 0.15)
				)
			)
		)
		(property "License" "Apache-2.0"
			(at 519.2 251 0)
			(layer "F.Fab")
			(hide yes)
			(effects
				(font
					(size 1 1)
					(thickness 0.15)
				)
			)
		)
		(property "MPN" "CR0402-FX-5101GLF"
			(at 519.2 251 0)
			(layer "F.Fab")
			(hide yes)
			(effects
				(font
					(size 1 1)
					(thickness 0.15)
				)
			)
		)
		(property "Manufacturer" "Bourns"
			(at 519.2 251 0)
			(layer "F.Fab")
			(hide yes)
			(effects
				(font
					(size 1 1)
					(thickness 0.15)
				)
			)
		)
		(property "Tolerance" "1%"
			(at 519.2 251 0)
			(layer "F.Fab")
			(hide yes)
			(effects
				(font
					(size 1 1)
					(thickness 0.15)
				)
			)
		)
		(property "Val" "5k1"
			(at 519.2 251 0)
			(layer "F.Fab")
			(hide yes)
			(effects
				(font
					(size 1 1)
					(thickness 0.15)
				)
			)
		)
		(sheetname "USB PHY")
		(sheetfile "usb-phy.kicad_sch")
		(attr smd)
		(fp_rect
			(start -0.925 -0.47)
			(end 0.925 0.47)
			(stroke
				(width 0.05)
				(type default)
			)
			(fill no)
			(layer "F.CrtYd")
		)
		(fp_rect
			(start -0.5 -0.25)
			(end 0.5 0.25)
			(stroke
				(width 0.15)
				(type solid)
			)
			(fill no)
			(layer "F.Fab")
		)
		(pad "1" smd roundrect
			(at -0.48 0 180)
			(size 0.59 0.64)
			(layers "F.Cu" "F.Mask" "F.Paste")
			(roundrect_rratio 0.25)
			(net 844 "/USB PHY/USB_USR_CC2")
			(pintype "passive")
		)
		(pad "2" smd roundrect
			(at 0.48 0 180)
			(size 0.59 0.64)
			(layers "F.Cu" "F.Mask" "F.Paste")
			(roundrect_rratio 0.25)
			(net 1 "GND")
			(pintype "passive")
		)
	)
	(footprint "antmicro-footprints:R_0402_1005Metric"
		(layer "F.Cu")
		(at 236.2 129.55 180)
		(descr "Resistor SMD 0402")
		(tags "resistor SMD 0402")
		(property "Reference" "R179"
			(at 1.825 3.525 180)
			(layer "F.SilkS")
			(effects
				(font
					(size 0.7 0.7)
					(thickness 0.15)
				)
				(justify left bottom)
			)
		)
		(property "Value" "R_33R_0402"
			(at 0 1.4 180)
			(layer "F.Fab")
			(effects
				(font
					(size 0.7 0.7)
					(thickness 0.15)
				)
				(justify left bottom)
			)
		)
		(property "Description" "SMD Chip Resistor, 33 ohm, ± 1%, 62.5 mW, 0402 [1005 Metric], Thick Film, General Purpose"
			(at 0 0 180)
			(layer "F.Fab")
			(hide yes)
			(effects
				(font
					(size 1.27 1.27)
					(thickness 0.15)
				)
			)
		)
		(property "Author" "Antmicro"
			(at 472.4 259.1 0)
			(layer "F.Fab")
			(hide yes)
			(effects
				(font
					(size 1 1)
					(thickness 0.15)
				)
			)
		)
		(property "License" "Apache-2.0"
			(at 472.4 259.1 0)
			(layer "F.Fab")
			(hide yes)
			(effects
				(font
					(size 1 1)
					(thickness 0.15)
				)
			)
		)
		(property "MPN" "CR0402-FX-33R0GLF"
			(at 472.4 259.1 0)
			(layer "F.Fab")
			(hide yes)
			(effects
				(font
					(size 1 1)
					(thickness 0.15)
				)
			)
		)
		(property "Manufacturer" "Bourns"
			(at 472.4 259.1 0)
			(layer "F.Fab")
			(hide yes)
			(effects
				(font
					(size 1 1)
					(thickness 0.15)
				)
			)
		)
		(property "Tolerance" "1%"
			(at 472.4 259.1 0)
			(layer "F.Fab")
			(hide yes)
			(effects
				(font
					(size 1 1)
					(thickness 0.15)
				)
			)
		)
		(property "Val" "33R"
			(at 472.4 259.1 0)
			(layer "F.Fab")
			(hide yes)
			(effects
				(font
					(size 1 1)
					(thickness 0.15)
				)
			)
		)
		(sheetname "USB PHY")
		(sheetfile "usb-phy.kicad_sch")
		(attr smd)
		(fp_rect
			(start -0.925 -0.47)
			(end 0.925 0.47)
			(stroke
				(width 0.05)
				(type default)
			)
			(fill no)
			(layer "F.CrtYd")
		)
		(fp_rect
			(start -0.5 -0.25)
			(end 0.5 0.25)
			(stroke
				(width 0.15)
				(type solid)
			)
			(fill no)
			(layer "F.Fab")
		)
		(pad "1" smd roundrect
			(at -0.48 0 180)
			(size 0.59 0.64)
			(layers "F.Cu" "F.Mask" "F.Paste")
			(roundrect_rratio 0.25)
			(net 371 "Net-(U22-B4)")
			(pintype "passive")
		)
		(pad "2" smd roundrect
			(at 0.48 0 180)
			(size 0.59 0.64)
			(layers "F.Cu" "F.Mask" "F.Paste")
			(roundrect_rratio 0.25)
			(net 190 "/FPGA Config/JTAG.TDO")
			(pintype "passive")
		)
	)
	(footprint "antmicro-footprints:C_0402_1005Metric"
		(layer "F.Cu")
		(at 260.3 135.7 90)
		(descr "Capacitor SMD 0402")
		(tags "capacitor SMD 0402")
		(property "Reference" "C224"
			(at -1.75 -0.45 90)
			(layer "F.SilkS")
			(effects
				(font
					(size 0.7 0.7)
					(thickness 0.15)
				)
				(justify left bottom)
			)
		)
		(property "Value" "C_100n_0402"
			(at 0 1.169 90)
			(layer "F.Fab")
			(effects
				(font
					(size 0.7 0.7)
					(thickness 0.15)
				)
				(justify left bottom)
			)
		)
		(property "Description" "SMD Multilayer Ceramic Capacitor, 0.1 µF, 50 V, 0402 [1005 Metric], ± 10%, X5R, GRM Series"
			(at 0 0 90)
			(layer "F.Fab")
			(hide yes)
			(effects
				(font
					(size 1.27 1.27)
					(thickness 0.15)
				)
			)
		)
		(property "Author" "Antmicro"
			(at 396 -124.6 0)
			(layer "F.Fab")
			(hide yes)
			(effects
				(font
					(size 1 1)
					(thickness 0.15)
				)
			)
		)
		(property "Dielectric" "X5R"
			(at 396 -124.6 0)
			(layer "F.Fab")
			(hide yes)
			(effects
				(font
					(size 1 1)
					(thickness 0.15)
				)
			)
		)
		(property "License" "Apache-2.0"
			(at 396 -124.6 0)
			(layer "F.Fab")
			(hide yes)
			(effects
				(font
					(size 1 1)
					(thickness 0.15)
				)
			)
		)
		(property "MPN" "GRM155R61H104KE14D"
			(at 396 -124.6 0)
			(layer "F.Fab")
			(hide yes)
			(effects
				(font
					(size 1 1)
					(thickness 0.15)
				)
			)
		)
		(property "Manufacturer" "Murata"
			(at 396 -124.6 0)
			(layer "F.Fab")
			(hide yes)
			(effects
				(font
					(size 1 1)
					(thickness 0.15)
				)
			)
		)
		(property "Val" "100n"
			(at 396 -124.6 0)
			(layer "F.Fab")
			(hide yes)
			(effects
				(font
					(size 1 1)
					(thickness 0.15)
				)
			)
		)
		(property "Voltage" "50V"
			(at 396 -124.6 0)
			(layer "F.Fab")
			(hide yes)
			(effects
				(font
					(size 1 1)
					(thickness 0.15)
				)
			)
		)
		(sheetname "USB PHY")
		(sheetfile "usb-phy.kicad_sch")
		(attr smd)
		(fp_rect
			(start -0.925 -0.47)
			(end 0.925 0.47)
			(stroke
				(width 0.05)
				(type default)
			)
			(fill no)
			(layer "F.CrtYd")
		)
		(fp_line
			(start 0.504 -0.25)
			(end 0.504 0.248)
			(stroke
				(width 0.15)
				(type solid)
			)
			(layer "F.Fab")
		)
		(fp_line
			(start -0.494 -0.25)
			(end 0.504 -0.25)
			(stroke
				(width 0.15)
				(type solid)
			)
			(layer "F.Fab")
		)
		(fp_line
			(start 0.504 0.248)
			(end -0.494 0.248)
			(stroke
				(width 0.15)
				(type solid)
			)
			(layer "F.Fab")
		)
		(fp_line
			(start -0.494 0.248)
			(end -0.494 -0.25)
			(stroke
				(width 0.15)
				(type solid)
			)
			(layer "F.Fab")
		)
		(pad "1" smd roundrect
			(at -0.48 0 90)
			(size 0.59 0.64)
			(layers "F.Cu" "F.Mask" "F.Paste")
			(roundrect_rratio 0.25)
			(net 1 "GND")
			(pintype "passive")
		)
		(pad "2" smd roundrect
			(at 0.48 0 90)
			(size 0.59 0.64)
			(layers "F.Cu" "F.Mask" "F.Paste")
			(roundrect_rratio 0.25)
			(net 707 "/USB PHY/FTDI_3V3")
			(pintype "passive")
		)
	)
	(footprint "antmicro-footprints:C_Pol_EIA-B"
		(layer "F.Cu")
		(at 206.15592 152.9)
		(property "Reference" "C133"
			(at -1.46592 2.6 0)
			(layer "F.SilkS")
			(effects
				(font
					(size 0.7 0.7)
					(thickness 0.15)
				)
				(justify left bottom)
			)
		)
		(property "Value" "C_Pol_330u_6.3V_KEMET-T520-B"
			(at -2.34 2.45 0)
			(layer "F.Fab")
			(effects
				(font
					(size 0.7 0.7)
					(thickness 0.15)
				)
				(justify left bottom)
			)
		)
		(property "Description" "Tantalum Polymer Capacitor, KO-CAP®, 330 µF, ± 20%, 6.3 V, B, 0.04 ohm, 1411 [3528 Metric]"
			(at 0 0 0)
			(layer "F.Fab")
			(hide yes)
			(effects
				(font
					(size 1.27 1.27)
					(thickness 0.15)
				)
			)
		)
		(property "Author" "Antmicro"
			(at 0 0 0)
			(layer "F.Fab")
			(hide yes)
			(effects
				(font
					(size 1 1)
					(thickness 0.15)
				)
			)
		)
		(property "Dielectric" ""
			(at 0 0 0)
			(layer "F.Fab")
			(hide yes)
			(effects
				(font
					(size 1 1)
					(thickness 0.15)
				)
			)
		)
		(property "License" "Apache-2.0"
			(at 0 0 0)
			(layer "F.Fab")
			(hide yes)
			(effects
				(font
					(size 1 1)
					(thickness 0.15)
				)
			)
		)
		(property "MPN" "T520B337M006ATE040"
			(at 0 0 0)
			(layer "F.Fab")
			(hide yes)
			(effects
				(font
					(size 1 1)
					(thickness 0.15)
				)
			)
		)
		(property "Manufacturer" "KEMET"
			(at 0 0 0)
			(layer "F.Fab")
			(hide yes)
			(effects
				(font
					(size 1 1)
					(thickness 0.15)
				)
			)
		)
		(property "Val" "330u"
			(at 0 0 0)
			(layer "F.Fab")
			(hide yes)
			(effects
				(font
					(size 1 1)
					(thickness 0.15)
				)
			)
		)
		(property "Voltage" "6.3V"
			(at 0 0 0)
			(layer "F.Fab")
			(hide yes)
			(effects
				(font
					(size 1 1)
					(thickness 0.15)
				)
			)
		)
		(sheetname "FPGA supply")
		(sheetfile "fpga-supply.kicad_sch")
		(attr smd)
		(fp_line
			(start -2.521 -1.676)
			(end -2.123 -1.676)
			(stroke
				(width 0.15)
				(type solid)
			)
			(layer "F.SilkS")
		)
		(fp_line
			(start -2.325 -1.475)
			(end -2.325 -1.878)
			(stroke
				(width 0.15)
				(type solid)
			)
			(layer "F.SilkS")
		)
		(fp_line
			(start -1.8 -1.6)
			(end 1.8 -1.6)
			(stroke
				(width 0.15)
				(type solid)
			)
			(layer "F.SilkS")
		)
		(fp_line
			(start -1.8 -1.3)
			(end -1.8 -1.6)
			(stroke
				(width 0.15)
				(type solid)
			)
			(layer "F.SilkS")
		)
		(fp_line
			(start -1.8 1.3)
			(end -1.8 1.6)
			(stroke
				(width 0.15)
				(type solid)
			)
			(layer "F.SilkS")
		)
		(fp_line
			(start 1.8 -1.3)
			(end 1.8 -1.6)
			(stroke
				(width 0.15)
				(type solid)
			)
			(layer "F.SilkS")
		)
		(fp_line
			(start 1.8 1.3)
			(end 1.8 1.6)
			(stroke
				(width 0.15)
				(type solid)
			)
			(layer "F.SilkS")
		)
		(fp_line
			(start 1.8 1.6)
			(end -1.8 1.6)
			(stroke
				(width 0.15)
				(type solid)
			)
			(layer "F.SilkS")
		)
		(fp_line
			(start -2.411 -1.35)
			(end -2.41 1.35)
			(stroke
				(width 0.05)
				(type solid)
			)
			(layer "F.CrtYd")
		)
		(fp_line
			(start -1.97 -1.75)
			(end -1.97 -1.35)
			(stroke
				(width 0.05)
				(type solid)
			)
			(layer "F.CrtYd")
		)
		(fp_line
			(start -1.97 -1.35)
			(end -2.41 -1.35)
			(stroke
				(width 0.05)
				(type solid)
			)
			(layer "F.CrtYd")
		)
		(fp_line
			(start -1.97 1.35)
			(end -2.41 1.35)
			(stroke
				(width 0.05)
				(type solid)
			)
			(layer "F.CrtYd")
		)
		(fp_line
			(start -1.97 1.35)
			(end -1.97 1.75)
			(stroke
				(width 0.05)
				(type solid)
			)
			(layer "F.CrtYd")
		)
		(fp_line
			(start 1.959 -1.75)
			(end -1.971 -1.75)
			(stroke
				(width 0.05)
				(type solid)
			)
			(layer "F.CrtYd")
		)
		(fp_line
			(start 1.959 -1.75)
			(end 1.959 -1.35)
			(stroke
				(width 0.05)
				(type solid)
			)
			(layer "F.CrtYd")
		)
		(fp_line
			(start 1.96 1.35)
			(end 1.96 1.75)
			(stroke
				(width 0.05)
				(type solid)
			)
			(layer "F.CrtYd")
		)
		(fp_line
			(start 1.96 1.75)
			(end -1.97 1.75)
			(stroke
				(width 0.05)
				(type solid)
			)
			(layer "F.CrtYd")
		)
		(fp_line
			(start 2.399 -1.35)
			(end 1.959 -1.35)
			(stroke
				(width 0.05)
				(type solid)
			)
			(layer "F.CrtYd")
		)
		(fp_line
			(start 2.399 -1.35)
			(end 2.4 1.35)
			(stroke
				(width 0.05)
				(type solid)
			)
			(layer "F.CrtYd")
		)
		(fp_line
			(start 2.4 1.35)
			(end 1.96 1.35)
			(stroke
				(width 0.05)
				(type solid)
			)
			(layer "F.CrtYd")
		)
		(fp_line
			(start -1.7 1.324)
			(end -1.551 1.475)
			(stroke
				(width 0.15)
				(type solid)
			)
			(layer "F.Fab")
		)
		(fp_rect
			(start -1.72 -1.5)
			(end 1.719 1.499)
			(stroke
				(width 0.15)
				(type solid)
			)
			(fill no)
			(layer "F.Fab")
		)
		(pad "1" smd roundrect
			(at -1.551 0)
			(size 1.2 2.2)
			(layers "F.Cu" "F.Mask" "F.Paste")
			(roundrect_rratio 0.1)
			(net 650 "+1V0")
			(pintype "passive")
		)
		(pad "2" smd roundrect
			(at 1.55 0)
			(size 1.2 2.2)
			(layers "F.Cu" "F.Mask" "F.Paste")
			(roundrect_rratio 0.1)
			(net 1 "GND")
			(pintype "passive")
		)
	)
)
